(kicad_pcb
	(version 20221018)
	(generator pcbnew)
	(general
    (thickness 1.7403)
  )
	(paper "A4")
	(title_block
    (title "Data Center RDIMM DDR4 Tester")
    (date "2024-09-30")
    (rev "1.2.4")
		(comment 9 "footprints 242-249 of 690")
	)
	(layers
    (0 "F.Cu" signal)
    (1 "In1.Cu" power)
    (2 "In2.Cu" signal)
    (3 "In3.Cu" power)
    (4 "In4.Cu" power)
    (5 "In5.Cu" signal)
    (6 "In6.Cu" power)
    (7 "In7.Cu" signal)
    (8 "In8.Cu" power)
    (9 "In9.Cu" signal)
    (10 "In10.Cu" power)
    (31 "B.Cu" signal)
    (32 "B.Adhes" user "B.Adhesive")
    (33 "F.Adhes" user "F.Adhesive")
    (34 "B.Paste" user)
    (35 "F.Paste" user)
    (36 "B.SilkS" user "B.Silkscreen")
    (37 "F.SilkS" user "F.Silkscreen")
    (38 "B.Mask" user)
    (39 "F.Mask" user)
    (40 "Dwgs.User" user "User.Drawings")
    (41 "Cmts.User" user "User.Comments")
    (42 "Eco1.User" user "User.Eco1")
    (43 "Eco2.User" user "User.Eco2")
    (44 "Edge.Cuts" user)
    (45 "Margin" user)
    (46 "B.CrtYd" user "B.Courtyard")
    (47 "F.CrtYd" user "F.Courtyard")
    (48 "B.Fab" user)
    (49 "F.Fab" user)
  )
	(footprint "data-center-rdimm-ddr4-tester-footprints:mounting-hole-3mm-NPTH" (layer "F.Cu")
    (at 256.75 133)
    (property "Author" "Antmicro")
    (property "License" "Apache-2.0")
    (property "MPN" "")
    (property "Manufacturer" "")
    (property "Sheetfile" "data-center-rdimm-ddr4-tester.kicad_sch")
    (property "Sheetname" "")
    (attr through_hole)
    (fp_text reference "MP2" (at 0 -1.8) (layer "F.SilkS") hide
        (effects (font (size 0.7 0.7) (thickness 0.15)) (justify left bottom))
    )
    (fp_text value "PCB_Mount_Hole_3mm_NPTH" (at 0 2.3) (layer "F.Fab") hide
        (effects (font (size 0.7 0.7) (thickness 0.15)) (justify left bottom))
    )
    (fp_text user "Author: Antmicro" (at 0 5.95) (layer "F.Fab") hide
        (effects (font (size 0.7 0.7) (thickness 0.15)) (justify left bottom))
    )
    (fp_text user "${REFERENCE}" (at 0 4.749) (layer "F.Fab") hide
        (effects (font (size 0.7 0.7) (thickness 0.15)) (justify left bottom))
    )
    (fp_text user "License: Apache-2.0" (at 0 7.15) (layer "F.Fab") hide
        (effects (font (size 0.7 0.7) (thickness 0.15)) (justify left bottom))
    )
    (pad "" np_thru_hole circle (at 0 0) (size 3 3) (drill 3) (layers "*.Cu" "*.Mask"))
  )
	(footprint "data-center-rdimm-ddr4-tester-footprints:R_0402_1005Metric" (layer "F.Cu")
    (at 224.295 86.75 180)
    (descr "Resistor SMD 0402")
    (tags "resistor SMD 0402")
    (property "Author" "Antmicro")
    (property "License" "Apache-2.0")
    (property "MPN" "CR0402-FX-1002GLF")
    (property "Manufacturer" "Bourns")
    (property "Sheetfile" "config-spi.kicad_sch")
    (property "Sheetname" "Config SPI flash")
    (property "Tolerance" "1%")
    (property "Val" "10k")
    (property "ki_description" "10k resistor in 0402 package with 1% tolerance")
    (attr smd)
    (fp_text reference "R193" (at 1.095 -2.52 180) (layer "F.SilkS")
        (effects (font (size 0.7 0.7) (thickness 0.15)) (justify left bottom))
    )
    (fp_text value "R_10k_0402" (at 0 1.4) (layer "F.Fab") hide
        (effects (font (size 0.7 0.7) (thickness 0.15)) (justify right bottom))
    )
    (fp_text user "License: Apache-2.0" (at -0.95 5.169) (layer "F.Fab") hide
        (effects (font (size 0.7 0.7) (thickness 0.15)) (justify right bottom))
    )
    (fp_text user "Author: Antmicro" (at -0.95 4.169) (layer "F.Fab") hide
        (effects (font (size 0.7 0.7) (thickness 0.15)) (justify right bottom))
    )
    (fp_text user "${REFERENCE}" (at -0.95 3.168) (layer "F.Fab") hide
        (effects (font (size 0.7 0.7) (thickness 0.15)) (justify right bottom))
    )
    (fp_rect (start -0.93 -0.47) (end 0.93 0.47)
      (stroke (width 0.05) (type solid)) (fill none) (layer "F.CrtYd"))
    (fp_rect (start -0.5 -0.25) (end 0.5 0.25)
      (stroke (width 0.15) (type solid)) (fill none) (layer "F.Fab"))
    (pad "1" smd roundrect (at -0.485 0 180) (size 0.59 0.64) (layers "F.Cu" "F.Paste" "F.Mask") (roundrect_rratio 0.25)
      (net 18 "MODE2") (pintype "passive"))
    (pad "2" smd roundrect (at 0.485 0 180) (size 0.59 0.64) (layers "F.Cu" "F.Paste" "F.Mask") (roundrect_rratio 0.25)
      (net 143 "3V3_SYS") (pintype "passive"))
  )
	(footprint "data-center-rdimm-ddr4-tester-footprints:R_0402_1005Metric" (layer "F.Cu")
    (at 219.85 122.35 90)
    (descr "Resistor SMD 0402")
    (tags "resistor SMD 0402")
    (property "Author" "Antmicro")
    (property "License" "Apache-2.0")
    (property "MPN" "CR0402-FX-1002GLF")
    (property "Manufacturer" "Bourns")
    (property "Sheetfile" "supply.kicad_sch")
    (property "Sheetname" "Supply")
    (property "Tolerance" "1%")
    (property "Val" "10k")
    (property "ki_description" "10k resistor in 0402 package with 1% tolerance")
    (attr smd)
    (fp_text reference "R123" (at -3.72 0.32 90) (layer "F.SilkS")
        (effects (font (size 0.7 0.7) (thickness 0.15)) (justify left bottom))
    )
    (fp_text value "R_10k_0402" (at 0 1.4 90) (layer "F.Fab") hide
        (effects (font (size 0.7 0.7) (thickness 0.15)) (justify left bottom))
    )
    (fp_text user "Author: Antmicro" (at -0.95 4.169 90) (layer "F.Fab") hide
        (effects (font (size 0.7 0.7) (thickness 0.15)) (justify left bottom))
    )
    (fp_text user "License: Apache-2.0" (at -0.95 5.169 90) (layer "F.Fab") hide
        (effects (font (size 0.7 0.7) (thickness 0.15)) (justify left bottom))
    )
    (fp_text user "${REFERENCE}" (at -0.95 3.168 90) (layer "F.Fab") hide
        (effects (font (size 0.7 0.7) (thickness 0.15)) (justify left bottom))
    )
    (fp_rect (start -0.93 -0.47) (end 0.93 0.47)
      (stroke (width 0.05) (type solid)) (fill none) (layer "F.CrtYd"))
    (fp_rect (start -0.5 -0.25) (end 0.5 0.25)
      (stroke (width 0.15) (type solid)) (fill none) (layer "F.Fab"))
    (pad "1" smd roundrect (at -0.485 0 90) (size 0.59 0.64) (layers "F.Cu" "F.Paste" "F.Mask") (roundrect_rratio 0.25)
      (net 167 "/Supply/SYS_EN") (pintype "passive"))
    (pad "2" smd roundrect (at 0.485 0 90) (size 0.59 0.64) (layers "F.Cu" "F.Paste" "F.Mask") (roundrect_rratio 0.25)
      (net 103 "VIN") (pintype "passive"))
  )
	(footprint "data-center-rdimm-ddr4-tester-footprints:C_0402_1005Metric" (layer "F.Cu")
    (at 156.175 104.425 -90)
    (descr "Capacitor SMD 0402")
    (tags "capacitor SMD 0402")
    (property "Author" "Antmicro")
    (property "DNP" "DNP")
    (property "Dielectric" "X5R")
    (property "License" "Apache-2.0")
    (property "MPN" "GRM155R61H104KE14D")
    (property "Manufacturer" "Murata")
    (property "Sheetfile" "ethernet.kicad_sch")
    (property "Sheetname" "Ethernet")
    (property "Val" "100n")
    (property "Voltage" "50V")
    (property "dnp" "")
    (property "exclude_from_bom" "")
    (property "ki_description" " ")
    (attr exclude_from_pos_files exclude_from_bom)
    (fp_text reference "C289" (at 3.685 -0.325 -90) (layer "F.SilkS")
        (effects (font (size 0.7 0.7) (thickness 0.15)) (justify left bottom))
    )
    (fp_text value "C_100n_0402" (at 0 1.4 -90) (layer "F.Fab") hide
        (effects (font (size 0.7 0.7) (thickness 0.15)) (justify left bottom))
    )
    (fp_text user "${REFERENCE}" (at -0.932 3.168 -90) (layer "F.Fab") hide
        (effects (font (size 0.7 0.7) (thickness 0.15)) (justify left bottom))
    )
    (fp_text user "License: Apache-2.0" (at -0.932 5.17 -90) (layer "F.Fab") hide
        (effects (font (size 0.7 0.7) (thickness 0.15)) (justify left bottom))
    )
    (fp_text user "Author: Antmicro" (at -0.932 4.17 -90) (layer "F.Fab") hide
        (effects (font (size 0.7 0.7) (thickness 0.15)) (justify left bottom))
    )
    (fp_rect (start -0.94 -0.47) (end 0.94 0.47)
      (stroke (width 0.05) (type solid)) (fill none) (layer "F.CrtYd"))
    (fp_rect (start -0.499 -0.249) (end 0.499 0.249)
      (stroke (width 0.15) (type solid)) (fill none) (layer "F.Fab"))
    (pad "1" smd roundrect (at -0.484 0 270) (size 0.59 0.64) (layers "F.Cu" "F.Paste" "F.Mask") (roundrect_rratio 0.25)
      (net 143 "3V3_SYS") (pintype "passive"))
    (pad "2" smd roundrect (at 0.484 0 270) (size 0.59 0.64) (layers "F.Cu" "F.Paste" "F.Mask") (roundrect_rratio 0.25)
      (net 9 "GND") (pintype "passive"))
  )
	(footprint "data-center-rdimm-ddr4-tester-footprints:RJ45_5-2337992-8_Horizontal" (layer "F.Cu")
    (at 159.785 118.116397)
    (property "Author" "Antmicro")
    (property "License" "Apache-2.0")
    (property "MPN" "5-2337992-8")
    (property "Manufacturer" "TE Connectivity")
    (property "Sheetfile" "ethernet.kicad_sch")
    (property "Sheetname" "Ethernet")
    (property "ki_description" "RJ45 Gigabit Ethernet Jack w/ Magnetics and PoE, Single Port, 802.3at Power over Ethernet")
    (property "ki_keywords" "RJ45 PoE Ethernet te connectivity magnetics gigabit power")
    (attr through_hole)
    (fp_text reference "J2" (at 5.165 -2.036397) (layer "F.SilkS")
        (effects (font (size 0.7 0.7) (thickness 0.15)) (justify left bottom))
    )
    (fp_text value "Bus_RJ45_5-2337992-8" (at -2.6 22) (layer "F.Fab") hide
        (effects (font (size 0.7 0.7) (thickness 0.15)) (justify left bottom))
    )
    (fp_text user "License: Apache-2.0" (at -2.644 26.2) (layer "F.Fab") hide
        (effects (font (size 0.7 0.7) (thickness 0.15)) (justify left bottom))
    )
    (fp_text user "${REFERENCE}" (at -2.644 23.4) (layer "F.Fab") hide
        (effects (font (size 0.7 0.7) (thickness 0.15)) (justify left bottom))
    )
    (fp_text user "Author: Antmicro" (at -2.644 24.8) (layer "F.Fab") hide
        (effects (font (size 0.7 0.7) (thickness 0.15)) (justify left bottom))
    )
    (fp_line (start -2.363 -1.845) (end -2.363 4.48)
      (stroke (width 0.15) (type solid)) (layer "F.SilkS"))
    (fp_line (start -2.363 7.217) (end -2.363 19.771)
      (stroke (width 0.15) (type solid)) (layer "F.SilkS"))
    (fp_line (start -2.363 19.771) (end 13.791 19.771)
      (stroke (width 0.15) (type solid)) (layer "F.SilkS"))
    (fp_line (start 13.791 -1.845) (end -2.363 -1.845)
      (stroke (width 0.15) (type solid)) (layer "F.SilkS"))
    (fp_line (start 13.791 4.48) (end 13.791 -1.845)
      (stroke (width 0.15) (type solid)) (layer "F.SilkS"))
    (fp_line (start 13.791 19.771) (end 13.791 7.217)
      (stroke (width 0.15) (type solid)) (layer "F.SilkS"))
    (fp_rect (start -2.4 -1.8) (end 13.9 19.999)
      (stroke (width 0.05) (type solid)) (fill none) (layer "F.CrtYd"))
    (fp_line (start -2.237 -1.718) (end -2.237 19.644)
      (stroke (width 0.15) (type solid)) (layer "F.Fab"))
    (fp_line (start -2.237 19.644) (end 13.665 19.644)
      (stroke (width 0.15) (type solid)) (layer "F.Fab"))
    (fp_line (start 13.665 -1.718) (end -2.237 -1.718)
      (stroke (width 0.15) (type solid)) (layer "F.Fab"))
    (fp_line (start 13.665 19.644) (end 13.665 -1.718)
      (stroke (width 0.15) (type solid)) (layer "F.Fab"))
    (pad "" np_thru_hole circle (at 0 8.9) (size 3.25 3.25) (drill 3.25) (layers "*.Cu" "*.Mask"))
    (pad "" np_thru_hole circle (at 11.429 8.9) (size 3.25 3.25) (drill 3.25) (layers "*.Cu" "*.Mask"))
    (pad "1" thru_hole circle (at 0 0) (size 1.397 1.397) (drill 0.889) (layers "*.Cu" "*.Mask")
      (net 631 "/Ethernet/INT_ETH1_P") (pinfunction "P1") (pintype "bidirectional"))
    (pad "2" thru_hole circle (at 1.269 2.539) (size 1.397 1.397) (drill 0.889) (layers "*.Cu" "*.Mask")
      (net 630 "/Ethernet/INT_ETH1_N") (pinfunction "P2") (pintype "bidirectional"))
    (pad "3" thru_hole circle (at 2.539 0) (size 1.397 1.397) (drill 0.889) (layers "*.Cu" "*.Mask")
      (net 568 "/Ethernet/INT_ETH2_P") (pinfunction "P3") (pintype "bidirectional"))
    (pad "4" thru_hole circle (at 3.809 2.539) (size 1.397 1.397) (drill 0.889) (layers "*.Cu" "*.Mask")
      (net 92 "Net-(J2-P4)") (pinfunction "P4") (pintype "bidirectional"))
    (pad "5" thru_hole circle (at 5.078 0) (size 1.397 1.397) (drill 0.889) (layers "*.Cu" "*.Mask")
      (net 94 "Net-(J2-P5)") (pinfunction "P5") (pintype "bidirectional"))
    (pad "6" thru_hole circle (at 6.349 2.539) (size 1.397 1.397) (drill 0.889) (layers "*.Cu" "*.Mask")
      (net 567 "/Ethernet/INT_ETH2_N") (pinfunction "P6") (pintype "bidirectional"))
    (pad "7" thru_hole circle (at 7.618 0) (size 1.397 1.397) (drill 0.889) (layers "*.Cu" "*.Mask")
      (net 559 "/Ethernet/INT_ETH3_P") (pinfunction "P7") (pintype "bidirectional"))
    (pad "8" thru_hole circle (at 8.89 2.539) (size 1.397 1.397) (drill 0.889) (layers "*.Cu" "*.Mask")
      (net 558 "/Ethernet/INT_ETH3_N") (pinfunction "P8") (pintype "bidirectional"))
    (pad "9" thru_hole circle (at 10.159 0) (size 1.397 1.397) (drill 0.889) (layers "*.Cu" "*.Mask")
      (net 548 "/Ethernet/INT_ETH4_P") (pinfunction "P9") (pintype "bidirectional"))
    (pad "10" thru_hole circle (at 11.429 2.539) (size 1.397 1.397) (drill 0.889) (layers "*.Cu" "*.Mask")
      (net 547 "/Ethernet/INT_ETH4_N") (pinfunction "P10") (pintype "bidirectional"))
    (pad "11" thru_hole circle (at 0 5.078) (size 1.397 1.397) (drill 0.889) (layers "*.Cu" "*.Mask")
      (net 605 "/Ethernet/PAIR_12") (pinfunction "VC1") (pintype "bidirectional"))
    (pad "12" thru_hole circle (at 2.539 6.339) (size 1.397 1.397) (drill 0.889) (layers "*.Cu" "*.Mask")
      (net 606 "/Ethernet/PAIR_36") (pinfunction "VC2") (pintype "bidirectional"))
    (pad "13" thru_hole circle (at 8.89 6.339) (size 1.397 1.397) (drill 0.889) (layers "*.Cu" "*.Mask")
      (net 607 "/Ethernet/PAIR_78") (pinfunction "VC3") (pintype "bidirectional"))
    (pad "14" thru_hole circle (at 11.429 5.07) (size 1.397 1.397) (drill 0.889) (layers "*.Cu" "*.Mask")
      (net 608 "/Ethernet/PAIR_910") (pinfunction "VC4") (pintype "bidirectional"))
    (pad "15" thru_hole circle (at -0.927 12.958) (size 1.524 1.524) (drill 1.016) (layers "*.Cu" "*.Mask")
      (net 112 "Net-(J2-LED_GRN+)") (pinfunction "LED_GRN+") (pintype "passive"))
    (pad "16" thru_hole circle (at 1.614 12.958) (size 1.524 1.524) (drill 1.016) (layers "*.Cu" "*.Mask")
      (net 546 "INT_LED_SPD") (pinfunction "LED_GRN-") (pintype "passive"))
    (pad "17" thru_hole circle (at 9.814 12.958) (size 1.524 1.524) (drill 1.016) (layers "*.Cu" "*.Mask")
      (net 113 "Net-(J2-LED_YEL+)") (pinfunction "LED_YEL+") (pintype "passive"))
    (pad "18" thru_hole circle (at 12.355 12.958) (size 1.524 1.524) (drill 1.016) (layers "*.Cu" "*.Mask")
      (net 537 "INT_LED_LINK") (pinfunction "LED_YEL-") (pintype "passive"))
    (pad "19" thru_hole circle (at -2.136 5.85) (size 2.1 2.1) (drill 1.6) (layers "*.Cu" "*.Mask")
      (net 862 "GNDS") (pinfunction "SHIELD") (pintype "passive"))
    (pad "20" thru_hole circle (at 13.563 5.85) (size 2.1082 2.1082) (drill 1.6002) (layers "*.Cu" "*.Mask")
      (net 862 "GNDS") (pinfunction "SHIELD") (pintype "passive"))
  )
	(footprint "data-center-rdimm-ddr4-tester-footprints:C_1206_3216Metric" (layer "F.Cu")
    (at 247.9 125.6 180)
    (descr "Capacitor SMD 1206")
    (tags "capacitor SMD 1206")
    (property "Author" "Antmicro")
    (property "Dielectric" "")
    (property "License" "Apache-2.0")
    (property "MPN" "C3216X5R1C476M160AB")
    (property "Manufacturer" "TDK")
    (property "Sheetfile" "fmc_hpc.kicad_sch")
    (property "Sheetname" "FMC HPC")
    (property "Val" "47u/16V")
    (property "Voltage" "")
    (property "ki_description" " ")
    (attr smd)
    (fp_text reference "C258" (at 1.47 -1.8 180) (layer "F.SilkS")
        (effects (font (size 0.7 0.7) (thickness 0.15)) (justify left bottom))
    )
    (fp_text value "C_47u_16V_1206" (at 0 2.1 180) (layer "F.Fab") hide
        (effects (font (size 0.7 0.7) (thickness 0.15)) (justify left bottom))
    )
    (fp_text user "License: Apache-2.0" (at -2.8 6.6 180) (layer "F.Fab") hide
        (effects (font (size 0.7 0.7) (thickness 0.15)) (justify left bottom))
    )
    (fp_text user "Author: Antmicro" (at -2.8 5.6 180) (layer "F.Fab") hide
        (effects (font (size 0.7 0.7) (thickness 0.15)) (justify left bottom))
    )
    (fp_text user "${REFERENCE}" (at -2.8 4.6 180) (layer "F.Fab") hide
        (effects (font (size 0.7 0.7) (thickness 0.15)) (justify left bottom))
    )
    (fp_line (start -2.625 -0.3) (end -2.625 0.3)
      (stroke (width 0.15) (type solid)) (layer "F.SilkS"))
    (fp_line (start 0.5 -0.9) (end -0.5 -0.9)
      (stroke (width 0.15) (type solid)) (layer "F.SilkS"))
    (fp_line (start 0.5 0.9) (end -0.5 0.9)
      (stroke (width 0.15) (type solid)) (layer "F.SilkS"))
    (fp_line (start 2.625 -0.3) (end 2.625 0.3)
      (stroke (width 0.15) (type solid)) (layer "F.SilkS"))
    (fp_rect (start -2.8 -1.15) (end 2.8 1.15)
      (stroke (width 0.05) (type solid)) (fill none) (layer "F.CrtYd"))
    (fp_rect (start -1.6 -0.8) (end 1.6 0.8)
      (stroke (width 0.15) (type solid)) (fill none) (layer "F.Fab"))
    (pad "1" smd rect (at -1.8 0 180) (size 1.5 1.8) (layers "F.Cu" "F.Paste" "F.Mask")
      (net 535 "12P0V") (pintype "passive"))
    (pad "2" smd rect (at 1.8 0 180) (size 1.5 1.8) (layers "F.Cu" "F.Paste" "F.Mask")
      (net 9 "GND") (pintype "passive"))
  )
	(footprint "data-center-rdimm-ddr4-tester-footprints:mounting-hole-3mm-NPTH" (layer "F.Cu")
    (at 110 49)
    (property "Author" "Antmicro")
    (property "License" "Apache-2.0")
    (property "MPN" "")
    (property "Manufacturer" "")
    (property "Sheetfile" "data-center-rdimm-ddr4-tester.kicad_sch")
    (property "Sheetname" "")
    (attr through_hole)
    (fp_text reference "MP4" (at 0 -1.8) (layer "F.SilkS") hide
        (effects (font (size 0.7 0.7) (thickness 0.15)) (justify left bottom))
    )
    (fp_text value "PCB_Mount_Hole_3mm_NPTH" (at 0 2.3) (layer "F.Fab") hide
        (effects (font (size 0.7 0.7) (thickness 0.15)) (justify left bottom))
    )
    (fp_text user "Author: Antmicro" (at 0 5.95) (layer "F.Fab") hide
        (effects (font (size 0.7 0.7) (thickness 0.15)) (justify left bottom))
    )
    (fp_text user "License: Apache-2.0" (at 0 7.15) (layer "F.Fab") hide
        (effects (font (size 0.7 0.7) (thickness 0.15)) (justify left bottom))
    )
    (fp_text user "${REFERENCE}" (at 0 4.749) (layer "F.Fab") hide
        (effects (font (size 0.7 0.7) (thickness 0.15)) (justify left bottom))
    )
    (pad "" np_thru_hole circle (at 0 0) (size 3 3) (drill 3) (layers "*.Cu" "*.Mask"))
  )
	(footprint "data-center-rdimm-ddr4-tester-footprints:TP_SMD_0.75mm" (layer "F.Cu")
    (at 250.7 122.5)
    (property "Author" "Antmicro")
    (property "License" "Apache-2.0")
    (property "MPN" "")
    (property "Manufacturer" "")
    (property "Sheetfile" "fmc_hpc.kicad_sch")
    (property "Sheetname" "FMC HPC")
    (property "ki_description" "Test Point 0.75mm")
    (attr exclude_from_pos_files)
    (fp_text reference "TP16" (at 0.51 0.35) (layer "F.SilkS")
        (effects (font (size 0.7 0.7) (thickness 0.15)) (justify left bottom))
    )
    (fp_text value "TP_0.75mm_SMD" (at 0 1.2) (layer "F.Fab") hide
        (effects (font (size 0.7 0.7) (thickness 0.15)) (justify left bottom))
    )
    (fp_text user "Author: Antmicro" (at -0.4 3.901) (layer "F.Fab") hide
        (effects (font (size 0.7 0.7) (thickness 0.15)) (justify left bottom))
    )
    (fp_text user "${REFERENCE}" (at -0.4 2.7) (layer "F.Fab") hide
        (effects (font (size 0.7 0.7) (thickness 0.15)) (justify left bottom))
    )
    (fp_text user "License: Apache-2.0" (at -0.4 5.101) (layer "F.Fab") hide
        (effects (font (size 0.7 0.7) (thickness 0.15)) (justify left bottom))
    )
    (pad "1" smd circle (at 0 0) (size 0.75 0.75) (layers "F.Cu" "F.Mask")
      (net 496 "Net-(J5B-VREF_{A_M2C})") (pinfunction "1") (pintype "passive"))
  )
)
